# TIMECARD (Time Appliance Project (Time Card)) — schematic netlist excerpt (pin names and nets, part order shuffled) for the footprints in the layout excerpt that follows; sources: Cadence DE-HDL packaged netlist, KiCad conversion of R4006-B0001-02_R01.brd

U17  CL1001485A  pkg SOT23_6  page 24
  \1\  = NC
  \2\  = SG
  \3\  = NC
  \4\  = FT_USB_DM
  \5\  = XP5R0V_FT4232
  \6\  = FT_USB_DP

(kicad_pcb
	(version 20260206)
	(generator "pcbnew")
	(generator_version "10.0")
	(general
		(thickness 1.6)
		(legacy_teardrops no)
	)
	(paper "A4")
	(title_block
		(title "timecard-production-celestica-r4006 — R4006-B0001-02_R01.brd")
		(comment 1 "Time Appliance Project (Time Card) / footprint 44 of 1113 (U17), pads 1-6 of 6")
	)
	(layers
		(0 "F.Cu" signal "TOP")
		(4 "In1.Cu" signal "L02_GND1")
		(6 "In2.Cu" signal "L03_SIG1")
		(8 "In3.Cu" signal "L04_GND2")
		(10 "In4.Cu" signal "L05_VCC1")
		(12 "In5.Cu" signal "L06_VCC2")
		(14 "In6.Cu" signal "L07_GND3")
		(16 "In7.Cu" signal "L08_SIG2")
		(18 "In8.Cu" signal "L09_GND4")
		(2 "B.Cu" signal "BOTTOM")
		(9 "F.Adhes" user "F.Adhesive")
		(11 "B.Adhes" user "B.Adhesive")
		(13 "F.Paste" user "Package Geometry/Pastemask Top")
		(15 "B.Paste" user "Package Geometry/Pastemask Bottom")
		(5 "F.SilkS" user "Ref Des/Silkscreen Top")
		(7 "B.SilkS" user "Ref Des/Silkscreen Bottom")
		(1 "F.Mask" user "Board Geometry/Soldermask Top")
		(3 "B.Mask" user "Board Geometry/Soldermask Bottom")
		(17 "Dwgs.User" user "User.Drawings")
		(19 "Cmts.User" user "User.Comments")
		(21 "Eco1.User" user "User.Eco1")
		(23 "Eco2.User" user "User.Eco2")
		(25 "Edge.Cuts" user "Board Geometry/Outline")
		(27 "Margin" user)
		(31 "F.CrtYd" user "Package Geometry/Place Bound Top")
		(29 "B.CrtYd" user "Package Geometry/Place Bound Bottom")
		(35 "F.Fab" user "Ref Des/Assembly Top")
		(33 "B.Fab" user "Ref Des/Assembly Bottom")
	)
	(footprint ""
		(layer "F.Cu")
		(at 18.288 -87.63 90)
		(property "Reference" "U17"
			(at -1.524 -2.50063 90)
			(unlocked yes)
			(layer "F.SilkS")
			(effects
				(font
					(size 0.7874 0.5842)
					(thickness 0.1524)
				)
			)
		)
		(property "Value" ""
			(at 0 0 90)
			(layer "F.Fab")
			(effects
				(font
					(size 1.27 1.27)
				)
			)
		)
		(property "User Part Number" "PARTNUM*"
			(at 0.1016 3.45567 90)
			(unlocked yes)
			(layer "Cmts.User")
			(hide yes)
			(effects
				(font
					(size 0.7874 0.5842)
					(thickness 0.1524)
				)
			)
		)
		(property "Device Type" "CL1001485A-G122-00019-01"
			(at 0.1016 2.54127 90)
			(unlocked yes)
			(layer "F.Fab")
			(hide yes)
			(effects
				(font
					(size 0.7874 0.5842)
					(thickness 0.1524)
				)
			)
		)
		(duplicate_pad_numbers_are_jumpers no)
		(pad "1" smd rect
			(at -1.4351 -0.94996 180)
			(size 0.508 1.1938)
			(layers "F.Cu" "F.Mask" "F.Paste")
			(net "Net_756")
		)
		(pad "2" smd rect
			(at -1.4351 0 180)
			(size 0.508 1.1938)
			(layers "F.Cu" "F.Mask" "F.Paste")
			(net "SG")
		)
		(pad "3" smd rect
			(at -1.4351 0.94996 180)
			(size 0.508 1.1938)
			(layers "F.Cu" "F.Mask" "F.Paste")
			(net "Net_755")
		)
		(pad "4" smd rect
			(at 1.4351 0.94996 180)
			(size 0.508 1.1938)
			(layers "F.Cu" "F.Mask" "F.Paste")
			(net "FT_USB_DM")
		)
		(pad "5" smd rect
			(at 1.4351 0 180)
			(size 0.508 1.1938)
			(layers "F.Cu" "F.Mask" "F.Paste")
			(net "XP5R0V_FT4232")
		)
		(pad "6" smd rect
			(at 1.4351 -0.94996 180)
			(size 0.508 1.1938)
			(layers "F.Cu" "F.Mask" "F.Paste")
			(net "FT_USB_DP")
		)
	)
)
